# T6G (Grand Teton) — schematic netlist excerpt (pin names and nets, part order shuffled) for the footprints in the layout excerpt that follows; sources: Cadence DE-HDL packaged netlist, KiCad conversion of 04192023_DAF0TMB3IC0_F0TG_MB_C_brd_V02_OCP.brd

C1860  Q_CAP  0.1UF 25V 10% X7R  pkg 0402  page 247 : A = P3V3_AUX ; B = GND
R3670  Q_RES  1K 1% CHIP  pkg 0402LF  page 257 : A = ADC128_A0 ; B = GND

(kicad_pcb
	(version 20260206)
	(generator "pcbnew")
	(generator_version "10.0")
	(general
		(thickness 1.6)
		(legacy_teardrops no)
	)
	(paper "A4")
	(title_block
		(title "04192023_DAF0TMB3IC0_F0TG_MB_C_brd_V02_OCP.brd")
		(comment 1 "Grand Teton / footprints 1372-1373 of 8354")
	)
	(layers
		(0 "F.Cu" signal "TOP")
		(4 "In1.Cu" signal "GND")
		(6 "In2.Cu" signal "IN1")
		(8 "In3.Cu" signal "GND1")
		(10 "In4.Cu" signal "IN2")
		(12 "In5.Cu" signal "GND2")
		(14 "In6.Cu" signal "IN3")
		(16 "In7.Cu" signal "GND3")
		(18 "In8.Cu" signal "VCC")
		(20 "In9.Cu" signal "VCC1")
		(22 "In10.Cu" signal "GND4")
		(24 "In11.Cu" signal "IN4")
		(26 "In12.Cu" signal "GND5")
		(28 "In13.Cu" signal "IN5")
		(30 "In14.Cu" signal "GND6")
		(32 "In15.Cu" signal "IN6")
		(34 "In16.Cu" signal "GND7")
		(2 "B.Cu" signal "BOTTOM")
		(9 "F.Adhes" user "F.Adhesive")
		(11 "B.Adhes" user "B.Adhesive")
		(13 "F.Paste" user "Package Geometry/Pastemask Top")
		(15 "B.Paste" user "Package Geometry/Pastemask Bottom")
		(5 "F.SilkS" user "Ref Des/Silkscreen Top")
		(7 "B.SilkS" user "Ref Des/Silkscreen Bottom")
		(1 "F.Mask" user "Board Geometry/Soldermask Top")
		(3 "B.Mask" user "Board Geometry/Soldermask Bottom")
		(17 "Dwgs.User" user "User.Drawings")
		(19 "Cmts.User" user "User.Comments")
		(21 "Eco1.User" user "User.Eco1")
		(23 "Eco2.User" user "User.Eco2")
		(25 "Edge.Cuts" user "Board Geometry/Outline")
		(27 "Margin" user)
		(31 "F.CrtYd" user "Package Geometry/Place Bound Top")
		(29 "B.CrtYd" user "Package Geometry/Place Bound Bottom")
		(35 "F.Fab" user "Ref Des/Assembly Top")
		(33 "B.Fab" user "Ref Des/Assembly Bottom")
	)
	(footprint ""
		(layer "F.Cu")
		(at 403.5552 -77.513434 90)
		(property "Reference" "C1860"
			(at 0 0 90)
			(layer "F.SilkS")
			(hide yes)
			(effects
				(font
					(size 1.27 1.27)
				)
			)
		)
		(property "Value" ""
			(at 0 0 90)
			(layer "F.Fab")
			(effects
				(font
					(size 1.27 1.27)
				)
			)
		)
		(duplicate_pad_numbers_are_jumpers no)
		(fp_line
			(start 0.7874 -0.4064)
			(end 0.7874 0.4064)
			(stroke
				(width 0.1524)
				(type default)
			)
			(layer "F.SilkS")
		)
		(fp_line
			(start -0.7874 -0.4064)
			(end 0.7874 -0.4064)
			(stroke
				(width 0.1524)
				(type default)
			)
			(layer "F.SilkS")
		)
		(fp_line
			(start 0.7874 0.4064)
			(end -0.7874 0.4064)
			(stroke
				(width 0.1524)
				(type default)
			)
			(layer "F.SilkS")
		)
		(fp_line
			(start -0.7874 0.4064)
			(end -0.7874 -0.4064)
			(stroke
				(width 0.1524)
				(type default)
			)
			(layer "F.SilkS")
		)
		(fp_line
			(start -0.12065 -0.305054)
			(end -0.12065 -0.2794)
			(stroke
				(width 0.1)
				(type default)
			)
			(layer "F.Fab")
		)
		(fp_line
			(start -0.67945 -0.305054)
			(end -0.12065 -0.305054)
			(stroke
				(width 0.1)
				(type default)
			)
			(layer "F.Fab")
		)
		(fp_line
			(start 0.67945 -0.3048)
			(end 0.67945 0.3048)
			(stroke
				(width 0.1)
				(type default)
			)
			(layer "F.Fab")
		)
		(fp_line
			(start 0.12065 -0.3048)
			(end 0.67945 -0.3048)
			(stroke
				(width 0.1)
				(type default)
			)
			(layer "F.Fab")
		)
		(fp_line
			(start 0.12065 -0.2794)
			(end 0.12065 -0.3048)
			(stroke
				(width 0.1)
				(type default)
			)
			(layer "F.Fab")
		)
		(fp_line
			(start -0.12065 -0.2794)
			(end 0.12065 -0.2794)
			(stroke
				(width 0.1)
				(type default)
			)
			(layer "F.Fab")
		)
		(fp_line
			(start 0.120396 0.2794)
			(end -0.12065 0.2794)
			(stroke
				(width 0.1)
				(type default)
			)
			(layer "F.Fab")
		)
		(fp_line
			(start -0.12065 0.2794)
			(end -0.12065 0.3048)
			(stroke
				(width 0.1)
				(type default)
			)
			(layer "F.Fab")
		)
		(fp_line
			(start 0.67945 0.3048)
			(end 0.120396 0.3048)
			(stroke
				(width 0.1)
				(type default)
			)
			(layer "F.Fab")
		)
		(fp_line
			(start 0.120396 0.3048)
			(end 0.120396 0.2794)
			(stroke
				(width 0.1)
				(type default)
			)
			(layer "F.Fab")
		)
		(fp_line
			(start -0.12065 0.3048)
			(end -0.67945 0.3048)
			(stroke
				(width 0.1)
				(type default)
			)
			(layer "F.Fab")
		)
		(fp_line
			(start -0.67945 0.3048)
			(end -0.67945 -0.305054)
			(stroke
				(width 0.1)
				(type default)
			)
			(layer "F.Fab")
		)
		(pad "1" smd circle
			(at -0.40005 0 90)
			(size 0 0)
			(layers "F.Cu" "F.Mask" "F.Paste")
			(net "P3V3_AUX")
		)
		(pad "2" smd circle
			(at 0.40005 0 90)
			(size 0 0)
			(layers "F.Cu" "F.Mask" "F.Paste")
			(net "GND")
		)
	)
	(footprint ""
		(layer "F.Cu")
		(at 305.819048 -41.906698 180)
		(property "Reference" "R3670"
			(at 0 0 180)
			(layer "F.SilkS")
			(hide yes)
			(effects
				(font
					(size 1.27 1.27)
				)
			)
		)
		(property "Value" ""
			(at 0 0 180)
			(layer "F.Fab")
			(effects
				(font
					(size 1.27 1.27)
				)
			)
		)
		(duplicate_pad_numbers_are_jumpers no)
		(fp_line
			(start 0.7874 0.4064)
			(end -0.7874 0.4064)
			(stroke
				(width 0.1524)
				(type default)
			)
			(layer "F.SilkS")
		)
		(fp_line
			(start 0.7874 -0.4064)
			(end 0.7874 0.4064)
			(stroke
				(width 0.1524)
				(type default)
			)
			(layer "F.SilkS")
		)
		(fp_line
			(start -0.7874 0.4064)
			(end -0.7874 -0.4064)
			(stroke
				(width 0.1524)
				(type default)
			)
			(layer "F.SilkS")
		)
		(fp_line
			(start -0.7874 -0.4064)
			(end 0.7874 -0.4064)
			(stroke
				(width 0.1524)
				(type default)
			)
			(layer "F.SilkS")
		)
		(fp_line
			(start 0.67945 0.3048)
			(end 0.120396 0.3048)
			(stroke
				(width 0.1)
				(type default)
			)
			(layer "F.Fab")
		)
		(fp_line
			(start 0.67945 -0.3048)
			(end 0.67945 0.3048)
			(stroke
				(width 0.1)
				(type default)
			)
			(layer "F.Fab")
		)
		(fp_line
			(start 0.12065 -0.2794)
			(end 0.12065 -0.3048)
			(stroke
				(width 0.1)
				(type default)
			)
			(layer "F.Fab")
		)
		(fp_line
			(start 0.12065 -0.3048)
			(end 0.67945 -0.3048)
			(stroke
				(width 0.1)
				(type default)
			)
			(layer "F.Fab")
		)
		(fp_line
			(start 0.120396 0.3048)
			(end 0.120396 0.2794)
			(stroke
				(width 0.1)
				(type default)
			)
			(layer "F.Fab")
		)
		(fp_line
			(start 0.120396 0.2794)
			(end -0.12065 0.2794)
			(stroke
				(width 0.1)
				(type default)
			)
			(layer "F.Fab")
		)
		(fp_line
			(start -0.12065 0.3048)
			(end -0.67945 0.3048)
			(stroke
				(width 0.1)
				(type default)
			)
			(layer "F.Fab")
		)
		(fp_line
			(start -0.12065 0.2794)
			(end -0.12065 0.3048)
			(stroke
				(width 0.1)
				(type default)
			)
			(layer "F.Fab")
		)
		(fp_line
			(start -0.12065 -0.2794)
			(end 0.12065 -0.2794)
			(stroke
				(width 0.1)
				(type default)
			)
			(layer "F.Fab")
		)
		(fp_line
			(start -0.12065 -0.305054)
			(end -0.12065 -0.2794)
			(stroke
				(width 0.1)
				(type default)
			)
			(layer "F.Fab")
		)
		(fp_line
			(start -0.67945 0.3048)
			(end -0.67945 -0.305054)
			(stroke
				(width 0.1)
				(type default)
			)
			(layer "F.Fab")
		)
		(fp_line
			(start -0.67945 -0.305054)
			(end -0.12065 -0.305054)
			(stroke
				(width 0.1)
				(type default)
			)
			(layer "F.Fab")
		)
		(pad "1" smd circle
			(at -0.40005 0 180)
			(size 0 0)
			(layers "F.Cu" "F.Mask" "F.Paste")
			(net "ADC128_A0")
		)
		(pad "2" smd circle
			(at 0.40005 0 180)
			(size 0 0)
			(layers "F.Cu" "F.Mask" "F.Paste")
			(net "GND")
		)
	)
)
